(kicad_pcb
	(version 20260206)
	(generator "pcbnew")
	(generator_version "10.0")
	(general
		(thickness 1.6)
		(legacy_teardrops no)
	)
	(paper "A4")
	(title_block
		(title "03242023_DA0F0TMBIJ0_F0T_Motherboard_J_brd_V01_OCP.brd")
		(comment 1 "Grand Teton / footprint 3039 of 6105 (U2), pads 3245-3347 of 4677")
	)
	(layers
		(0 "F.Cu" signal "TOP")
		(4 "In1.Cu" signal "GND")
		(6 "In2.Cu" signal "IN1")
		(8 "In3.Cu" signal "GND1")
		(10 "In4.Cu" signal "IN2")
		(12 "In5.Cu" signal "GND2")
		(14 "In6.Cu" signal "IN3")
		(16 "In7.Cu" signal "GND3")
		(18 "In8.Cu" signal "VCC")
		(20 "In9.Cu" signal "VCC1")
		(22 "In10.Cu" signal "GND4")
		(24 "In11.Cu" signal "IN4")
		(26 "In12.Cu" signal "GND5")
		(28 "In13.Cu" signal "IN5")
		(30 "In14.Cu" signal "GND6")
		(32 "In15.Cu" signal "IN6")
		(34 "In16.Cu" signal "GND7")
		(2 "B.Cu" signal "BOTTOM")
		(9 "F.Adhes" user "F.Adhesive")
		(11 "B.Adhes" user "B.Adhesive")
		(13 "F.Paste" user "Package Geometry/Pastemask Top")
		(15 "B.Paste" user "Package Geometry/Pastemask Bottom")
		(5 "F.SilkS" user "Ref Des/Silkscreen Top")
		(7 "B.SilkS" user "Ref Des/Silkscreen Bottom")
		(1 "F.Mask" user "Board Geometry/Soldermask Top")
		(3 "B.Mask" user "Board Geometry/Soldermask Bottom")
		(17 "Dwgs.User" user "User.Drawings")
		(19 "Cmts.User" user "User.Comments")
		(21 "Eco1.User" user "User.Eco1")
		(23 "Eco2.User" user "User.Eco2")
		(25 "Edge.Cuts" user "Board Geometry/Outline")
		(27 "Margin" user)
		(31 "F.CrtYd" user "Package Geometry/Place Bound Top")
		(29 "B.CrtYd" user "Package Geometry/Place Bound Bottom")
		(35 "F.Fab" user "Ref Des/Assembly Top")
		(33 "B.Fab" user "Ref Des/Assembly Bottom")
	)
	(footprint ""
		(layer "F.Cu")
		(at 359.870248 -251.76988 90)
		(property "Reference" "U2"
			(at -74.416158 -44.488608 0)
			(unlocked yes)
			(layer "F.SilkS")
			(effects
				(font
					(size 1.6002 1.1938)
					(thickness 0.1524)
				)
				(justify left)
			)
		)
		(property "Value" ""
			(at 0 0 90)
			(layer "F.Fab")
			(effects
				(font
					(size 1.27 1.27)
				)
			)
		)
		(duplicate_pad_numbers_are_jumpers no)
		(pad "DW90" smd circle
			(at 36.611306 19.086068 270)
			(size 0.4318 0.4318)
			(layers "F.Cu" "F.Mask" "F.Paste")
			(net "P5E_CPU0_PE3_RX_DP<4>")
		)
		(pad "DY2" smd circle
			(at -36.611306 19.445732 270)
			(size 0.4318 0.4318)
			(layers "F.Cu" "F.Mask" "F.Paste")
			(net "UPI_CPU1_CPU0_P0P1_DN<4>")
		)
		(pad "DY4" smd circle
			(at -34.98342 19.445732 270)
			(size 0.4318 0.4318)
			(layers "F.Cu" "F.Mask" "F.Paste")
			(net "GND")
		)
		(pad "DY6" smd circle
			(at -33.355534 19.445732 270)
			(size 0.4318 0.4318)
			(layers "F.Cu" "F.Mask" "F.Paste")
			(net "UPI_CPU0_CPU1_P1P0_DP<3>")
		)
		(pad "DY8" smd circle
			(at -31.727902 19.445732 270)
			(size 0.4318 0.4318)
			(layers "F.Cu" "F.Mask" "F.Paste")
			(net "GND")
		)
		(pad "DY10" smd circle
			(at -30.100016 19.445732 270)
			(size 0.4318 0.4318)
			(layers "F.Cu" "F.Mask" "F.Paste")
			(net "P5E_CPU0_PE2_RX_DN<11>")
		)
		(pad "DY12" smd circle
			(at -28.472384 19.445732 270)
			(size 0.4318 0.4318)
			(layers "F.Cu" "F.Mask" "F.Paste")
			(net "GND")
		)
		(pad "DY14" smd circle
			(at -26.844498 19.445732 270)
			(size 0.4318 0.4318)
			(layers "F.Cu" "F.Mask" "F.Paste")
			(net "P5E_CPU0_PE2_TX_DP<12>")
		)
		(pad "DY16" smd circle
			(at -25.216612 19.445732 270)
			(size 0.4318 0.4318)
			(layers "F.Cu" "F.Mask" "F.Paste")
			(net "GND")
		)
		(pad "DY18" smd circle
			(at -23.58898 19.445732 270)
			(size 0.4318 0.4318)
			(layers "F.Cu" "F.Mask" "F.Paste")
			(net "M_F_CPU0_SB_DQS_DN<8>")
		)
		(pad "DY20" smd circle
			(at -21.961094 19.445732 270)
			(size 0.4318 0.4318)
			(layers "F.Cu" "F.Mask" "F.Paste")
			(net "M_F_CPU0_SB_DQ<26>")
		)
		(pad "DY22" smd circle
			(at -20.333462 19.445732 270)
			(size 0.4318 0.4318)
			(layers "F.Cu" "F.Mask" "F.Paste")
			(net "M_G_CPU0_SB_DQ<23>")
		)
		(pad "DY24" smd circle
			(at -18.705576 19.445732 270)
			(size 0.4318 0.4318)
			(layers "F.Cu" "F.Mask" "F.Paste")
			(net "M_G_CPU0_SB_DQS_DP<7>")
		)
		(pad "DY26" smd circle
			(at -17.07769 19.445732 270)
			(size 0.4318 0.4318)
			(layers "F.Cu" "F.Mask" "F.Paste")
			(net "M_G_CPU0_SB_DQ<18>")
		)
		(pad "DY28" smd circle
			(at -15.450058 19.445732 270)
			(size 0.4318 0.4318)
			(layers "F.Cu" "F.Mask" "F.Paste")
			(net "M_F_CPU0_SB_DQ<7>")
		)
		(pad "DY30" smd circle
			(at -13.822426 19.445732 270)
			(size 0.4318 0.4318)
			(layers "F.Cu" "F.Mask" "F.Paste")
			(net "M_F_CPU0_SB_DQS_DP<5>")
		)
		(pad "DY32" smd circle
			(at -12.19454 19.445732 270)
			(size 0.4318 0.4318)
			(layers "F.Cu" "F.Mask" "F.Paste")
			(net "M_F_CPU0_SB_DQ<2>")
		)
		(pad "DY34" smd circle
			(at -10.566654 19.445732 270)
			(size 0.4318 0.4318)
			(layers "F.Cu" "F.Mask" "F.Paste")
			(net "M_G_CPU0_SB_CB<3>")
		)
		(pad "DY36" smd circle
			(at -8.939022 19.445732 270)
			(size 0.4318 0.4318)
			(layers "F.Cu" "F.Mask" "F.Paste")
			(net "M_G_CPU0_SB_DQS_DP<4>")
		)
		(pad "DY38" smd circle
			(at -7.311136 19.445732 270)
			(size 0.4318 0.4318)
			(layers "F.Cu" "F.Mask" "F.Paste")
			(net "M_G_CPU0_SB_CB<6>")
		)
		(pad "DY40" smd circle
			(at -5.68325 19.445732 270)
			(size 0.4318 0.4318)
			(layers "F.Cu" "F.Mask" "F.Paste")
			(net "M_G_CPU0_SB_CS_N<1>")
		)
		(pad "DY42" smd circle
			(at -4.055618 19.445732 270)
			(size 0.4318 0.4318)
			(layers "F.Cu" "F.Mask" "F.Paste")
			(net "GND")
		)
		(pad "DY44" smd circle
			(at -2.427732 19.445732 270)
			(size 0.4318 0.4318)
			(layers "F.Cu" "F.Mask" "F.Paste")
			(net "M_G_CPU0_SB_CA<3>")
		)
		(pad "DY47" smd circle
			(at 1.613916 19.555714 270)
			(size 0.4318 0.4318)
			(layers "F.Cu" "F.Mask" "F.Paste")
			(net "M_G_CPU0_SA_RSP<1>")
		)
		(pad "DY49" smd circle
			(at 3.241802 19.555714 270)
			(size 0.4318 0.4318)
			(layers "F.Cu" "F.Mask" "F.Paste")
			(net "M_F_CPU0_CLK_DN<0>")
		)
		(pad "DY51" smd circle
			(at 4.869434 19.555714 270)
			(size 0.4318 0.4318)
			(layers "F.Cu" "F.Mask" "F.Paste")
			(net "M_F_CPU0_SA_CA<6>")
		)
		(pad "DY53" smd circle
			(at 6.49732 19.555714 270)
			(size 0.4318 0.4318)
			(layers "F.Cu" "F.Mask" "F.Paste")
			(net "M_F_CPU0_SA_DQ<31>")
		)
		(pad "DY55" smd circle
			(at 8.124952 19.555714 270)
			(size 0.4318 0.4318)
			(layers "F.Cu" "F.Mask" "F.Paste")
			(net "M_F_CPU0_SA_DQS_DP<8>")
		)
		(pad "DY57" smd circle
			(at 9.752838 19.555714 270)
			(size 0.4318 0.4318)
			(layers "F.Cu" "F.Mask" "F.Paste")
			(net "M_F_CPU0_SA_DQ<26>")
		)
		(pad "DY59" smd circle
			(at 11.380724 19.555714 270)
			(size 0.4318 0.4318)
			(layers "F.Cu" "F.Mask" "F.Paste")
			(net "M_G_CPU0_SA_DQ<23>")
		)
		(pad "DY61" smd circle
			(at 13.008356 19.555714 270)
			(size 0.4318 0.4318)
			(layers "F.Cu" "F.Mask" "F.Paste")
			(net "M_G_CPU0_SA_DQS_DP<7>")
		)
		(pad "DY63" smd circle
			(at 14.635988 19.555714 270)
			(size 0.4318 0.4318)
			(layers "F.Cu" "F.Mask" "F.Paste")
			(net "M_G_CPU0_SA_DQ<18>")
		)
		(pad "DY65" smd circle
			(at 16.263874 19.555714 270)
			(size 0.4318 0.4318)
			(layers "F.Cu" "F.Mask" "F.Paste")
			(net "M_F_CPU0_SA_DQ<15>")
		)
		(pad "DY67" smd circle
			(at 17.89176 19.555714 270)
			(size 0.4318 0.4318)
			(layers "F.Cu" "F.Mask" "F.Paste")
			(net "M_F_CPU0_SA_DQS_DP<6>")
		)
		(pad "DY69" smd circle
			(at 19.519392 19.555714 270)
			(size 0.4318 0.4318)
			(layers "F.Cu" "F.Mask" "F.Paste")
			(net "M_F_CPU0_SA_DQ<10>")
		)
		(pad "DY71" smd circle
			(at 21.147278 19.555714 270)
			(size 0.4318 0.4318)
			(layers "F.Cu" "F.Mask" "F.Paste")
			(net "M_G_CPU0_SA_DQ<7>")
		)
		(pad "DY73" smd circle
			(at 22.77491 19.555714 270)
			(size 0.4318 0.4318)
			(layers "F.Cu" "F.Mask" "F.Paste")
			(net "M_G_CPU0_SA_DQS_DP<5>")
		)
		(pad "DY75" smd circle
			(at 24.402796 19.555714 270)
			(size 0.4318 0.4318)
			(layers "F.Cu" "F.Mask" "F.Paste")
			(net "M_G_CPU0_SA_DQ<2>")
		)
		(pad "DY77" smd circle
			(at 26.030682 19.555714 270)
			(size 0.4318 0.4318)
			(layers "F.Cu" "F.Mask" "F.Paste")
			(net "GND")
		)
		(pad "DY79" smd circle
			(at 27.658314 19.555714 270)
			(size 0.4318 0.4318)
			(layers "F.Cu" "F.Mask" "F.Paste")
			(net "M_H_CPU0_SA_DQ<0>")
		)
		(pad "DY81" smd circle
			(at 29.2862 19.555714 270)
			(size 0.4318 0.4318)
			(layers "F.Cu" "F.Mask" "F.Paste")
			(net "GND")
		)
		(pad "DY83" smd circle
			(at 30.914086 19.555714 270)
			(size 0.4318 0.4318)
			(layers "F.Cu" "F.Mask" "F.Paste")
			(net "GND")
		)
		(pad "DY85" smd circle
			(at 32.541718 19.555714 270)
			(size 0.4318 0.4318)
			(layers "F.Cu" "F.Mask" "F.Paste")
			(net "PVCCFA_EHV_FIVRA_CPU0")
		)
		(pad "DY87" smd circle
			(at 34.169604 19.555714 270)
			(size 0.4318 0.4318)
			(layers "F.Cu" "F.Mask" "F.Paste")
			(net "P5E_CPU0_PE3_TX_DN<2>")
		)
		(pad "DY89" smd circle
			(at 35.797236 19.555714 270)
			(size 0.4318 0.4318)
			(layers "F.Cu" "F.Mask" "F.Paste")
			(net "PVCCFA_EHV_FIVRA_CPU0")
		)
		(pad "DY91" smd oval
			(at 37.425122 19.555714)
			(size 0.381 0.4826)
			(drill
				(offset 0 -0.0508)
			)
			(layers "F.Cu" "F.Mask" "F.Paste")
			(net "P5E_CPU0_PE3_RX_DN<3>")
		)
		(pad "E5" smd oval
			(at -34.169604 -25.194514 135)
			(size 0.381 0.4826)
			(drill
				(offset 0 -0.0508)
			)
			(layers "F.Cu" "F.Mask" "F.Paste")
			(net "GND")
		)
		(pad "E7" smd oval
			(at -32.541718 -25.194514 135)
			(size 0.381 0.4826)
			(drill
				(offset 0 -0.0508)
			)
			(layers "F.Cu" "F.Mask" "F.Paste")
			(net "M_A_CPU0_SB_DQ<31>")
		)
		(pad "E9" smd circle
			(at -30.914086 -25.194514 270)
			(size 0.4318 0.4318)
			(layers "F.Cu" "F.Mask" "F.Paste")
			(net "M_A_CPU0_SB_DQS_DP<8>")
		)
		(pad "E11" smd circle
			(at -29.2862 -25.194514 270)
			(size 0.4318 0.4318)
			(layers "F.Cu" "F.Mask" "F.Paste")
			(net "M_A_CPU0_SB_DQ<26>")
		)
		(pad "E13" smd circle
			(at -27.658314 -25.194514 270)
			(size 0.4318 0.4318)
			(layers "F.Cu" "F.Mask" "F.Paste")
			(net "M_B_CPU0_SB_DQ<29>")
		)
		(pad "E15" smd circle
			(at -26.030682 -25.194514 270)
			(size 0.4318 0.4318)
			(layers "F.Cu" "F.Mask" "F.Paste")
			(net "M_B_CPU0_SB_DQS_DN<8>")
		)
		(pad "E17" smd circle
			(at -24.402796 -25.194514 270)
			(size 0.4318 0.4318)
			(layers "F.Cu" "F.Mask" "F.Paste")
			(net "M_B_CPU0_SB_DQ<26>")
		)
		(pad "E19" smd circle
			(at -22.77491 -25.194514 270)
			(size 0.4318 0.4318)
			(layers "F.Cu" "F.Mask" "F.Paste")
			(net "M_A_CPU0_SB_DQ<23>")
		)
		(pad "E21" smd circle
			(at -21.147278 -25.194514 270)
			(size 0.4318 0.4318)
			(layers "F.Cu" "F.Mask" "F.Paste")
			(net "M_A_CPU0_SB_DQS_DP<7>")
		)
		(pad "E23" smd circle
			(at -19.519392 -25.194514 270)
			(size 0.4318 0.4318)
			(layers "F.Cu" "F.Mask" "F.Paste")
			(net "M_A_CPU0_SB_DQ<18>")
		)
		(pad "E25" smd circle
			(at -17.89176 -25.194514 270)
			(size 0.4318 0.4318)
			(layers "F.Cu" "F.Mask" "F.Paste")
			(net "M_A_CPU0_SB_DQ<15>")
		)
		(pad "E27" smd circle
			(at -16.263874 -25.194514 270)
			(size 0.4318 0.4318)
			(layers "F.Cu" "F.Mask" "F.Paste")
			(net "M_A_CPU0_SB_DQS_DP<6>")
		)
		(pad "E29" smd circle
			(at -14.635988 -25.194514 270)
			(size 0.4318 0.4318)
			(layers "F.Cu" "F.Mask" "F.Paste")
			(net "M_A_CPU0_SB_DQ<10>")
		)
		(pad "E31" smd circle
			(at -13.008356 -25.194514 270)
			(size 0.4318 0.4318)
			(layers "F.Cu" "F.Mask" "F.Paste")
			(net "M_A_CPU0_SB_CB<3>")
		)
		(pad "E33" smd circle
			(at -11.380724 -25.194514 270)
			(size 0.4318 0.4318)
			(layers "F.Cu" "F.Mask" "F.Paste")
			(net "M_A_CPU0_SB_DQS_DP<4>")
		)
		(pad "E35" smd circle
			(at -9.752838 -25.194514 270)
			(size 0.4318 0.4318)
			(layers "F.Cu" "F.Mask" "F.Paste")
			(net "M_A_CPU0_SB_CB<6>")
		)
		(pad "E37" smd circle
			(at -8.124952 -25.194514 270)
			(size 0.4318 0.4318)
			(layers "F.Cu" "F.Mask" "F.Paste")
			(net "M_A_CPU0_SB_CS_N<3>")
		)
		(pad "E39" smd circle
			(at -6.49732 -25.194514 270)
			(size 0.4318 0.4318)
			(layers "F.Cu" "F.Mask" "F.Paste")
			(net "GND")
		)
		(pad "E41" smd circle
			(at -4.869434 -25.194514 270)
			(size 0.4318 0.4318)
			(layers "F.Cu" "F.Mask" "F.Paste")
			(net "M_A_CPU0_SB_CA<3>")
		)
		(pad "E43" smd circle
			(at -3.241802 -25.194514 270)
			(size 0.4318 0.4318)
			(layers "F.Cu" "F.Mask" "F.Paste")
			(net "M_A_CPU0_SB_CA<0>")
		)
		(pad "E45" smd circle
			(at -1.613916 -25.194514 270)
			(size 0.4318 0.4318)
			(layers "F.Cu" "F.Mask" "F.Paste")
			(net "M_A_CPU0_CLK_DP<1>")
		)
		(pad "E48" smd circle
			(at 2.427732 -25.084532 270)
			(size 0.4318 0.4318)
			(layers "F.Cu" "F.Mask" "F.Paste")
			(net "M_A_CPU0_SA_PAR")
		)
		(pad "E50" smd circle
			(at 4.055618 -25.084532 270)
			(size 0.4318 0.4318)
			(layers "F.Cu" "F.Mask" "F.Paste")
			(net "M_A_CPU0_SA_CA<5>")
		)
		(pad "E52" smd circle
			(at 5.68325 -25.084532 270)
			(size 0.4318 0.4318)
			(layers "F.Cu" "F.Mask" "F.Paste")
			(net "GND")
		)
		(pad "E54" smd circle
			(at 7.311136 -25.084532 270)
			(size 0.4318 0.4318)
			(layers "F.Cu" "F.Mask" "F.Paste")
			(net "M_A_CPU0_SA_CS_N<2>")
		)
		(pad "E56" smd circle
			(at 8.939022 -25.084532 270)
			(size 0.4318 0.4318)
			(layers "F.Cu" "F.Mask" "F.Paste")
			(net "M_A_CPU0_SA_CB<7>")
		)
		(pad "E58" smd circle
			(at 10.566654 -25.084532 270)
			(size 0.4318 0.4318)
			(layers "F.Cu" "F.Mask" "F.Paste")
			(net "M_A_CPU0_SA_DQS_DP<9>")
		)
		(pad "E60" smd circle
			(at 12.19454 -25.084532 270)
			(size 0.4318 0.4318)
			(layers "F.Cu" "F.Mask" "F.Paste")
			(net "M_A_CPU0_SA_CB<2>")
		)
		(pad "E62" smd circle
			(at 13.822426 -25.084532 270)
			(size 0.4318 0.4318)
			(layers "F.Cu" "F.Mask" "F.Paste")
			(net "M_A_CPU0_SA_DQ<31>")
		)
		(pad "E64" smd circle
			(at 15.450058 -25.084532 270)
			(size 0.4318 0.4318)
			(layers "F.Cu" "F.Mask" "F.Paste")
			(net "M_A_CPU0_SA_DQS_DP<8>")
		)
		(pad "E66" smd circle
			(at 17.07769 -25.084532 270)
			(size 0.4318 0.4318)
			(layers "F.Cu" "F.Mask" "F.Paste")
			(net "M_A_CPU0_SA_DQ<26>")
		)
		(pad "E68" smd circle
			(at 18.705576 -25.084532 270)
			(size 0.4318 0.4318)
			(layers "F.Cu" "F.Mask" "F.Paste")
			(net "M_A_CPU0_SA_DQ<23>")
		)
		(pad "E70" smd circle
			(at 20.333462 -25.084532 270)
			(size 0.4318 0.4318)
			(layers "F.Cu" "F.Mask" "F.Paste")
			(net "M_A_CPU0_SA_DQS_DP<7>")
		)
		(pad "E72" smd circle
			(at 21.961094 -25.084532 270)
			(size 0.4318 0.4318)
			(layers "F.Cu" "F.Mask" "F.Paste")
			(net "M_A_CPU0_SA_DQ<17>")
		)
		(pad "E74" smd circle
			(at 23.58898 -25.084532 270)
			(size 0.4318 0.4318)
			(layers "F.Cu" "F.Mask" "F.Paste")
			(net "GND")
		)
		(pad "E76" smd circle
			(at 25.216612 -25.084532 270)
			(size 0.4318 0.4318)
			(layers "F.Cu" "F.Mask" "F.Paste")
			(net "GND")
		)
		(pad "E78" smd circle
			(at 26.844498 -25.084532 270)
			(size 0.4318 0.4318)
			(layers "F.Cu" "F.Mask" "F.Paste")
			(net "GND")
		)
		(pad "E80" smd circle
			(at 28.472384 -25.084532 270)
			(size 0.4318 0.4318)
			(layers "F.Cu" "F.Mask" "F.Paste")
			(net "UPI_CPU1_CPU0_P2P2_DN<23>")
		)
		(pad "E82" smd circle
			(at 30.100016 -25.084532 270)
			(size 0.4318 0.4318)
			(layers "F.Cu" "F.Mask" "F.Paste")
			(net "UPI_CPU1_CPU0_P2P2_DN<22>")
		)
		(pad "E84" smd circle
			(at 31.727902 -25.084532 270)
			(size 0.4318 0.4318)
			(layers "F.Cu" "F.Mask" "F.Paste")
			(net "UPI_CPU0_CPU1_P2P2_DN<22>")
		)
		(pad "E86" smd oval
			(at 33.355534 -25.084532 45)
			(size 0.381 0.4826)
			(drill
				(offset 0 -0.0508)
			)
			(layers "F.Cu" "F.Mask" "F.Paste")
			(net "GND")
		)
		(pad "E88" smd oval
			(at 34.98342 -25.084532 45)
			(size 0.381 0.4826)
			(drill
				(offset 0 -0.0508)
			)
			(layers "F.Cu" "F.Mask" "F.Paste")
			(net "UPI_CPU0_CPU1_P2P2_DP<21>")
		)
		(pad "EA1" smd oval
			(at -37.425122 19.915886 180)
			(size 0.381 0.4826)
			(drill
				(offset 0 -0.0508)
			)
			(layers "F.Cu" "F.Mask" "F.Paste")
			(net "UPI_CPU1_CPU0_P0P1_DN<3>")
		)
		(pad "EA3" smd circle
			(at -35.797236 19.915886 270)
			(size 0.4318 0.4318)
			(layers "F.Cu" "F.Mask" "F.Paste")
			(net "PVCCFA_EHV_FIVRA_CPU0")
		)
		(pad "EA5" smd circle
			(at -34.169604 19.915886 270)
			(size 0.4318 0.4318)
			(layers "F.Cu" "F.Mask" "F.Paste")
			(net "UPI_CPU0_CPU1_P1P0_DP<2>")
		)
		(pad "EA7" smd circle
			(at -32.541718 19.915886 270)
			(size 0.4318 0.4318)
			(layers "F.Cu" "F.Mask" "F.Paste")
			(net "PVCCFA_EHV_FIVRA_CPU0")
		)
		(pad "EA9" smd circle
			(at -30.914086 19.915886 270)
			(size 0.4318 0.4318)
			(layers "F.Cu" "F.Mask" "F.Paste")
			(net "P5E_CPU0_PE2_RX_DN<12>")
		)
		(pad "EA11" smd circle
			(at -29.2862 19.915886 270)
			(size 0.4318 0.4318)
			(layers "F.Cu" "F.Mask" "F.Paste")
			(net "PVCCFA_EHV_FIVRA_CPU0")
		)
		(pad "EA13" smd circle
			(at -27.658314 19.915886 270)
			(size 0.4318 0.4318)
			(layers "F.Cu" "F.Mask" "F.Paste")
			(net "P5E_CPU0_PE2_TX_DN<12>")
		)
		(pad "EA15" smd circle
			(at -26.030682 19.915886 270)
			(size 0.4318 0.4318)
			(layers "F.Cu" "F.Mask" "F.Paste")
			(net "PVCCFA_EHV_FIVRA_CPU0")
		)
		(pad "EA17" smd circle
			(at -24.402796 19.915886 270)
			(size 0.4318 0.4318)
			(layers "F.Cu" "F.Mask" "F.Paste")
			(net "M_F_CPU0_SB_DQ<28>")
		)
		(pad "EA19" smd circle
			(at -22.77491 19.915886 270)
			(size 0.4318 0.4318)
			(layers "F.Cu" "F.Mask" "F.Paste")
			(net "M_F_CPU0_SB_DQ<27>")
		)
		(pad "EA21" smd circle
			(at -21.147278 19.915886 270)
			(size 0.4318 0.4318)
			(layers "F.Cu" "F.Mask" "F.Paste")
			(net "GND")
		)
		(pad "EA23" smd circle
			(at -19.519392 19.915886 270)
			(size 0.4318 0.4318)
			(layers "F.Cu" "F.Mask" "F.Paste")
			(net "M_G_CPU0_SB_DQ<22>")
		)
		(pad "EA25" smd circle
			(at -17.89176 19.915886 270)
			(size 0.4318 0.4318)
			(layers "F.Cu" "F.Mask" "F.Paste")
			(net "M_G_CPU0_SB_DQ<19>")
		)
		(pad "EA27" smd circle
			(at -16.263874 19.915886 270)
			(size 0.4318 0.4318)
			(layers "F.Cu" "F.Mask" "F.Paste")
			(net "GND")
		)
		(pad "EA29" smd circle
			(at -14.635988 19.915886 270)
			(size 0.4318 0.4318)
			(layers "F.Cu" "F.Mask" "F.Paste")
			(net "M_F_CPU0_SB_DQ<6>")
		)
	)
)
